(kicad_pcb
	(version 20260206)
	(generator "pcbnew")
	(generator_version "10.0")
	(general
		(thickness 1.6)
		(legacy_teardrops no)
	)
	(paper "A4")
	(title_block
		(title "m-2 — Lightning_M.2_BRD.brd")
		(comment 1 "Lightning (Wiwynn / Facebook NVMe JBOF) / footprints 1-8 of 157")
	)
	(layers
		(0 "F.Cu" signal "TOP")
		(4 "In1.Cu" signal "L2GND")
		(6 "In2.Cu" signal "L3")
		(8 "In3.Cu" signal "L4GND")
		(10 "In4.Cu" signal "L5GND")
		(12 "In5.Cu" signal "L6")
		(14 "In6.Cu" signal "L7GND")
		(2 "B.Cu" signal "BOTTOM")
		(9 "F.Adhes" user "F.Adhesive")
		(11 "B.Adhes" user "B.Adhesive")
		(13 "F.Paste" user "Package Geometry/Pastemask Top")
		(15 "B.Paste" user "Package Geometry/Pastemask Bottom")
		(5 "F.SilkS" user "Ref Des/Silkscreen Top")
		(7 "B.SilkS" user "Ref Des/Silkscreen Bottom")
		(1 "F.Mask" user "Board Geometry/Soldermask Top")
		(3 "B.Mask" user "Board Geometry/Soldermask Bottom")
		(17 "Dwgs.User" user "User.Drawings")
		(19 "Cmts.User" user "User.Comments")
		(21 "Eco1.User" user "User.Eco1")
		(23 "Eco2.User" user "User.Eco2")
		(25 "Edge.Cuts" user "Board Geometry/Outline")
		(27 "Margin" user)
		(31 "F.CrtYd" user "Package Geometry/Place Bound Top")
		(29 "B.CrtYd" user "Package Geometry/Place Bound Bottom")
		(35 "F.Fab" user "Ref Des/Assembly Top")
		(33 "B.Fab" user "Ref Des/Assembly Bottom")
	)
	(footprint ""
		(layer "F.Cu")
		(at 20.447 -84.122006 90)
		(property "Reference" "PC27"
			(at 0 0 90)
			(layer "F.SilkS")
			(hide yes)
			(effects
				(font
					(size 1.27 1.27)
				)
			)
		)
		(property "Value" "SC22U6D3V5MX-5-GP"
			(at -0.0762 -6.1214 90)
			(unlocked yes)
			(layer "F.Fab")
			(hide yes)
			(effects
				(font
					(size 1.016 1.016)
					(thickness 0.1524)
				)
			)
		)
		(property "Device Type" "C805H56"
			(at -0.0762 -8.1534 90)
			(unlocked yes)
			(layer "F.Fab")
			(hide yes)
			(effects
				(font
					(size 1.016 1.016)
					(thickness 0.1524)
				)
			)
		)
		(duplicate_pad_numbers_are_jumpers no)
		(fp_line
			(start 0.635 0)
			(end -0.635 0)
			(stroke
				(width 0.508)
				(type default)
			)
			(layer "F.SilkS")
		)
		(fp_rect
			(start -0.9652 1.778)
			(end 0.9652 -1.778)
			(stroke
				(width 0)
				(type default)
			)
			(fill no)
			(layer "F.CrtYd")
		)
		(fp_poly
			(pts
				(xy -0.9652 -1.778) (xy 0.9652 -1.778) (xy 0.9652 1.778) (xy -0.9652 1.778)
			)
			(stroke
				(width 0)
				(type default)
			)
			(fill no)
			(layer "F.Fab")
		)
		(pad "1" smd rect
			(at 0 -0.9652 90)
			(size 1.397 1.143)
			(layers "F.Cu" "F.Mask" "F.Paste")
			(net "P3V3_PWR")
		)
		(pad "2" smd rect
			(at 0 0.9652 90)
			(size 1.397 1.143)
			(layers "F.Cu" "F.Mask" "F.Paste")
			(net "GND")
		)
	)
	(footprint ""
		(layer "F.Cu")
		(at 76.708 -76.327 -90)
		(property "Reference" "CN1"
			(at 0 0 270)
			(layer "F.SilkS")
			(hide yes)
			(effects
				(font
					(size 1.27 1.27)
				)
			)
		)
		(property "Value" "CLX-CON3-S2-GP"
			(at -5.103876 -0.705866 270)
			(unlocked yes)
			(layer "F.Fab")
			(hide yes)
			(effects
				(font
					(size 1.016 1.016)
					(thickness 0.1524)
				)
			)
		)
		(property "Device Type" "CH31032V2S6"
			(at -5.103876 -2.229866 270)
			(unlocked yes)
			(layer "F.Fab")
			(hide yes)
			(effects
				(font
					(size 1.016 1.016)
					(thickness 0.1524)
				)
			)
		)
		(duplicate_pad_numbers_are_jumpers no)
		(fp_line
			(start -3.9751 1.524)
			(end -3.9751 -1.524)
			(stroke
				(width 0.1524)
				(type default)
			)
			(layer "F.SilkS")
		)
		(fp_line
			(start 3.9751 1.524)
			(end -3.9751 1.524)
			(stroke
				(width 0.1524)
				(type default)
			)
			(layer "F.SilkS")
		)
		(fp_line
			(start -3.9751 -1.524)
			(end 3.9751 -1.524)
			(stroke
				(width 0.1524)
				(type default)
			)
			(layer "F.SilkS")
		)
		(fp_line
			(start 3.9751 -1.524)
			(end 3.9751 1.524)
			(stroke
				(width 0.1524)
				(type default)
			)
			(layer "F.SilkS")
		)
		(fp_line
			(start -4.1021 -1.651)
			(end -4.1021 -0.381)
			(stroke
				(width 0.4064)
				(type default)
			)
			(layer "F.SilkS")
		)
		(fp_line
			(start -2.8321 -1.651)
			(end -4.1021 -1.651)
			(stroke
				(width 0.4064)
				(type default)
			)
			(layer "F.SilkS")
		)
		(fp_circle
			(center -2.54 0)
			(end -2.54 -1.0668)
			(stroke
				(width 0.3048)
				(type default)
			)
			(fill no)
			(layer "F.SilkS")
		)
		(fp_circle
			(center 0 0)
			(end 0 -1.0668)
			(stroke
				(width 0.3048)
				(type default)
			)
			(fill no)
			(layer "F.SilkS")
		)
		(fp_circle
			(center 2.54 0)
			(end 2.54 -1.0668)
			(stroke
				(width 0.3048)
				(type default)
			)
			(fill no)
			(layer "F.SilkS")
		)
		(fp_rect
			(start -3.7211 1.27)
			(end 3.7211 -1.27)
			(stroke
				(width 0)
				(type default)
			)
			(fill no)
			(layer "F.CrtYd")
		)
		(fp_poly
			(pts
				(xy -4.2291 1.778) (xy -4.2291 -1.778) (xy 4.2291 -1.778) (xy 4.2291 1.778) (xy 0.00254 1.778) (xy 0.00254 1.27)
				(xy 3.7211 1.27) (xy 3.7211 -1.27) (xy -3.7211 -1.27) (xy -3.7211 1.27) (xy -0.00254 1.27) (xy -0.00254 1.778)
			)
			(stroke
				(width 0)
				(type default)
			)
			(fill no)
			(layer "F.CrtYd")
		)
		(fp_rect
			(start -4.2291 1.778)
			(end 4.2291 -1.778)
			(stroke
				(width 0)
				(type default)
			)
			(fill no)
			(layer "F.Fab")
		)
		(pad "1" thru_hole circle
			(at -2.54 0 270)
			(size 1.4224 1.4224)
			(drill 1.016)
			(layers "*.Cu" "*.Mask")
			(remove_unused_layers no)
			(net "GND")
			(clearance 0.1524)
			(thermal_gap 0.1524)
		)
		(pad "2" thru_hole circle
			(at 0 0 270)
			(size 1.4224 1.4224)
			(drill 1.016)
			(layers "*.Cu" "*.Mask")
			(remove_unused_layers no)
			(net "Z50_SSD_A1_SMB_CLK")
			(clearance 0.1524)
			(thermal_gap 0.1524)
		)
		(pad "3" thru_hole circle
			(at 2.54 0 270)
			(size 1.4224 1.4224)
			(drill 1.016)
			(layers "*.Cu" "*.Mask")
			(remove_unused_layers no)
			(net "Z50_SSD_A1_SMB_DATA")
			(clearance 0.1524)
			(thermal_gap 0.1524)
		)
	)
	(footprint ""
		(layer "F.Cu")
		(at 59.817 -35.179 -90)
		(property "Reference" "C32"
			(at 0 0 270)
			(layer "F.SilkS")
			(hide yes)
			(effects
				(font
					(size 1.27 1.27)
				)
			)
		)
		(property "Value" "SCD1U16V2KX-3GP"
			(at 1.1811 -2.7051 270)
			(unlocked yes)
			(layer "F.Fab")
			(hide yes)
			(effects
				(font
					(size 1.016 1.016)
					(thickness 0.1524)
				)
			)
		)
		(property "Device Type" "C402H22"
			(at 1.1811 -4.2291 270)
			(unlocked yes)
			(layer "F.Fab")
			(hide yes)
			(effects
				(font
					(size 1.016 1.016)
					(thickness 0.1524)
				)
			)
		)
		(duplicate_pad_numbers_are_jumpers no)
		(fp_rect
			(start -0.4318 0.9525)
			(end 0.4318 -0.9525)
			(stroke
				(width 0)
				(type default)
			)
			(fill no)
			(layer "F.CrtYd")
		)
		(fp_rect
			(start -0.4318 0.9525)
			(end 0.4318 -0.9525)
			(stroke
				(width 0)
				(type default)
			)
			(fill no)
			(layer "F.Fab")
		)
		(pad "1" smd custom
			(at 0 -0.4445 270)
			(size 0.1524 0.1524)
			(layers "F.Cu" "F.Mask" "F.Paste")
			(net "P3V3_PWR")
			(options
				(clearance outline)
				(anchor circle)
			)
			(primitives
				(gr_poly
					(pts
						(arc
							(start 0.3048 -0.2032)
							(mid 0.275042 -0.275042)
							(end 0.2032 -0.3048)
						)
						(arc
							(start -0.2032 -0.3048)
							(mid -0.275042 -0.275042)
							(end -0.3048 -0.2032)
						)
						(arc
							(start -0.3048 0.2032)
							(mid -0.275042 0.275042)
							(end -0.2032 0.3048)
						)
						(arc
							(start 0.2032 0.3048)
							(mid 0.275042 0.275042)
							(end 0.3048 0.2032)
						)
					)
					(width 0)
					(fill yes)
				)
			)
		)
		(pad "2" smd custom
			(at 0 0.4445 270)
			(size 0.1524 0.1524)
			(layers "F.Cu" "F.Mask" "F.Paste")
			(net "GND")
			(options
				(clearance outline)
				(anchor circle)
			)
			(primitives
				(gr_poly
					(pts
						(arc
							(start 0.3048 -0.2032)
							(mid 0.275042 -0.275042)
							(end 0.2032 -0.3048)
						)
						(arc
							(start -0.2032 -0.3048)
							(mid -0.275042 -0.275042)
							(end -0.3048 -0.2032)
						)
						(arc
							(start -0.3048 0.2032)
							(mid -0.275042 0.275042)
							(end -0.2032 0.3048)
						)
						(arc
							(start 0.2032 0.3048)
							(mid 0.275042 0.275042)
							(end 0.3048 0.2032)
						)
					)
					(width 0)
					(fill yes)
				)
			)
		)
	)
	(footprint ""
		(layer "F.Cu")
		(at 6.500114 -80.309974)
		(property "Reference" "H2"
			(at 0 0 0)
			(layer "F.SilkS")
			(hide yes)
			(effects
				(font
					(size 1.27 1.27)
				)
			)
		)
		(property "Value" "HOLE315R140-GP"
			(at 0 -7.5692 0)
			(unlocked yes)
			(layer "F.Fab")
			(hide yes)
			(effects
				(font
					(size 1.016 1.016)
					(thickness 0.1524)
				)
			)
		)
		(property "Device Type" "HOLE315R140"
			(at 0 -9.0932 0)
			(unlocked yes)
			(layer "F.Fab")
			(hide yes)
			(effects
				(font
					(size 1.016 1.016)
					(thickness 0.1524)
				)
			)
		)
		(duplicate_pad_numbers_are_jumpers no)
		(fp_poly
			(pts
				(arc
					(start 4.3053 0)
					(mid -4.3053 0)
					(end 4.3053 0)
				)
			)
			(stroke
				(width 0)
				(type default)
			)
			(fill no)
			(layer "F.CrtYd")
		)
		(fp_poly
			(pts
				(arc
					(start 4.3053 0)
					(mid -4.3053 0)
					(end 4.3053 0)
				)
			)
			(stroke
				(width 0)
				(type default)
			)
			(fill no)
			(layer "F.Fab")
		)
		(pad "1" thru_hole circle
			(at 0.00127 0.00127)
			(size 8.001 8.001)
			(drill 3.556)
			(layers "*.Cu" "*.Mask")
			(remove_unused_layers no)
			(net "GND")
			(clearance -1.7145)
			(thermal_gap 0.3048)
			(padstack
				(mode front_inner_back)
				(layer "Inner"
					(shape circle)
					(size 3.9624 3.9624)
					(clearance 0.3048)
				)
				(layer "B.Cu"
					(shape circle)
					(size 8.001 8.001)
					(clearance -1.7145)
				)
			)
		)
	)
	(footprint ""
		(layer "F.Cu")
		(at 65.786 -75.184 90)
		(property "Reference" "PC42"
			(at 0 0 90)
			(layer "F.SilkS")
			(hide yes)
			(effects
				(font
					(size 1.27 1.27)
				)
			)
		)
		(property "Value" "SC10U6D3V5KX-4GP"
			(at -0.0762 -6.1214 90)
			(unlocked yes)
			(layer "F.Fab")
			(hide yes)
			(effects
				(font
					(size 1.016 1.016)
					(thickness 0.1524)
				)
			)
		)
		(property "Device Type" "C805H58"
			(at -0.0762 -8.1534 90)
			(unlocked yes)
			(layer "F.Fab")
			(hide yes)
			(effects
				(font
					(size 1.016 1.016)
					(thickness 0.1524)
				)
			)
		)
		(duplicate_pad_numbers_are_jumpers no)
		(fp_line
			(start 0.635 0)
			(end -0.635 0)
			(stroke
				(width 0.508)
				(type default)
			)
			(layer "F.SilkS")
		)
		(fp_rect
			(start -0.9652 1.778)
			(end 0.9652 -1.778)
			(stroke
				(width 0)
				(type default)
			)
			(fill no)
			(layer "F.CrtYd")
		)
		(fp_poly
			(pts
				(xy -0.9652 -1.778) (xy 0.9652 -1.778) (xy 0.9652 1.778) (xy -0.9652 1.778)
			)
			(stroke
				(width 0)
				(type default)
			)
			(fill no)
			(layer "F.Fab")
		)
		(pad "1" smd rect
			(at 0 -0.9652 90)
			(size 1.397 1.143)
			(layers "F.Cu" "F.Mask" "F.Paste")
			(net "P3V3_PWR")
		)
		(pad "2" smd rect
			(at 0 0.9652 90)
			(size 1.397 1.143)
			(layers "F.Cu" "F.Mask" "F.Paste")
			(net "GND")
		)
	)
	(footprint ""
		(layer "F.Cu")
		(at 25.527 -86.535006)
		(property "Reference" "C7"
			(at 0 0 0)
			(layer "F.SilkS")
			(hide yes)
			(effects
				(font
					(size 1.27 1.27)
				)
			)
		)
		(property "Value" "SCD1U16V2KX-3GP"
			(at 1.1811 -2.7051 0)
			(unlocked yes)
			(layer "F.Fab")
			(hide yes)
			(effects
				(font
					(size 1.016 1.016)
					(thickness 0.1524)
				)
			)
		)
		(property "Device Type" "C402H22"
			(at 1.1811 -4.2291 0)
			(unlocked yes)
			(layer "F.Fab")
			(hide yes)
			(effects
				(font
					(size 1.016 1.016)
					(thickness 0.1524)
				)
			)
		)
		(duplicate_pad_numbers_are_jumpers no)
		(fp_rect
			(start -0.4318 0.9525)
			(end 0.4318 -0.9525)
			(stroke
				(width 0)
				(type default)
			)
			(fill no)
			(layer "F.CrtYd")
		)
		(fp_rect
			(start -0.4318 0.9525)
			(end 0.4318 -0.9525)
			(stroke
				(width 0)
				(type default)
			)
			(fill no)
			(layer "F.Fab")
		)
		(pad "1" smd custom
			(at 0 -0.4445)
			(size 0.1524 0.1524)
			(layers "F.Cu" "F.Mask" "F.Paste")
			(net "P3V3_DPB")
			(options
				(clearance outline)
				(anchor circle)
			)
			(primitives
				(gr_poly
					(pts
						(arc
							(start 0.3048 -0.2032)
							(mid 0.275042 -0.275042)
							(end 0.2032 -0.3048)
						)
						(arc
							(start -0.2032 -0.3048)
							(mid -0.275042 -0.275042)
							(end -0.3048 -0.2032)
						)
						(arc
							(start -0.3048 0.2032)
							(mid -0.275042 0.275042)
							(end -0.2032 0.3048)
						)
						(arc
							(start 0.2032 0.3048)
							(mid 0.275042 0.275042)
							(end 0.3048 0.2032)
						)
					)
					(width 0)
					(fill yes)
				)
			)
		)
		(pad "2" smd custom
			(at 0 0.4445)
			(size 0.1524 0.1524)
			(layers "F.Cu" "F.Mask" "F.Paste")
			(net "GND")
			(options
				(clearance outline)
				(anchor circle)
			)
			(primitives
				(gr_poly
					(pts
						(arc
							(start 0.3048 -0.2032)
							(mid 0.275042 -0.275042)
							(end 0.2032 -0.3048)
						)
						(arc
							(start -0.2032 -0.3048)
							(mid -0.275042 -0.275042)
							(end -0.3048 -0.2032)
						)
						(arc
							(start -0.3048 0.2032)
							(mid -0.275042 0.275042)
							(end -0.2032 0.3048)
						)
						(arc
							(start 0.2032 0.3048)
							(mid 0.275042 0.275042)
							(end 0.3048 0.2032)
						)
					)
					(width 0)
					(fill yes)
				)
			)
		)
	)
	(footprint ""
		(layer "F.Cu")
		(at 25.019 -81.534 90)
		(property "Reference" "R28"
			(at 0 0 90)
			(layer "F.SilkS")
			(hide yes)
			(effects
				(font
					(size 1.27 1.27)
				)
			)
		)
		(property "Value" "4K7R2F-GP"
			(at 0.064008 -3.993896 90)
			(unlocked yes)
			(layer "F.Fab")
			(hide yes)
			(effects
				(font
					(size 1.016 1.016)
					(thickness 0.1524)
				)
			)
		)
		(property "Device Type" "R402H16"
			(at 0.064008 -5.517896 90)
			(unlocked yes)
			(layer "F.Fab")
			(hide yes)
			(effects
				(font
					(size 1.016 1.016)
					(thickness 0.1524)
				)
			)
		)
		(duplicate_pad_numbers_are_jumpers no)
		(fp_line
			(start 0.508 -0.9398)
			(end -0.508 -0.9398)
			(stroke
				(width 0.1524)
				(type default)
			)
			(layer "F.SilkS")
		)
		(fp_line
			(start -0.508 -0.9398)
			(end -0.508 0.9398)
			(stroke
				(width 0.1524)
				(type default)
			)
			(layer "F.SilkS")
		)
		(fp_rect
			(start -0.508 0.9398)
			(end 0.508 -0.9398)
			(stroke
				(width 0)
				(type default)
			)
			(fill no)
			(layer "F.CrtYd")
		)
		(fp_rect
			(start -0.508 0.9398)
			(end 0.508 -0.9398)
			(stroke
				(width 0)
				(type default)
			)
			(fill no)
			(layer "F.Fab")
		)
		(pad "1" smd custom
			(at 0 -0.4445 90)
			(size 0.1397 0.1397)
			(layers "F.Cu" "F.Mask" "F.Paste")
			(net "P3V3_DPB")
			(options
				(clearance outline)
				(anchor circle)
			)
			(primitives
				(gr_poly
					(pts
						(arc
							(start -0.1778 -0.2794)
							(mid -0.249642 -0.249642)
							(end -0.2794 -0.1778)
						)
						(arc
							(start -0.2794 0.1778)
							(mid -0.249642 0.249642)
							(end -0.1778 0.2794)
						)
						(arc
							(start 0.1778 0.2794)
							(mid 0.249642 0.249642)
							(end 0.2794 0.1778)
						)
						(arc
							(start 0.2794 -0.1778)
							(mid 0.249642 -0.249642)
							(end 0.1778 -0.2794)
						)
					)
					(width 0)
					(fill yes)
				)
			)
		)
		(pad "2" smd custom
			(at 0 0.4445 90)
			(size 0.1397 0.1397)
			(layers "F.Cu" "F.Mask" "F.Paste")
			(net "Z50_SMB_SWITCH_ADDRESS_A1")
			(options
				(clearance outline)
				(anchor circle)
			)
			(primitives
				(gr_poly
					(pts
						(arc
							(start -0.1778 -0.2794)
							(mid -0.249642 -0.249642)
							(end -0.2794 -0.1778)
						)
						(arc
							(start -0.2794 0.1778)
							(mid -0.249642 0.249642)
							(end -0.1778 0.2794)
						)
						(arc
							(start 0.1778 0.2794)
							(mid 0.249642 0.249642)
							(end 0.2794 0.1778)
						)
						(arc
							(start 0.2794 -0.1778)
							(mid 0.249642 -0.249642)
							(end 0.1778 -0.2794)
						)
					)
					(width 0)
					(fill yes)
				)
			)
		)
	)
	(footprint ""
		(layer "F.Cu")
		(at 51.7144 -75.692)
		(property "Reference" "C267"
			(at 0 0 0)
			(layer "F.SilkS")
			(hide yes)
			(effects
				(font
					(size 1.27 1.27)
				)
			)
		)
		(property "Value" "SC100P50V2JN-3GP"
			(at 1.1811 -2.7051 0)
			(unlocked yes)
			(layer "F.Fab")
			(hide yes)
			(effects
				(font
					(size 1.016 1.016)
					(thickness 0.1524)
				)
			)
		)
		(property "Device Type" "C402H22"
			(at 1.1811 -4.2291 0)
			(unlocked yes)
			(layer "F.Fab")
			(hide yes)
			(effects
				(font
					(size 1.016 1.016)
					(thickness 0.1524)
				)
			)
		)
		(duplicate_pad_numbers_are_jumpers no)
		(fp_rect
			(start -0.4318 0.9525)
			(end 0.4318 -0.9525)
			(stroke
				(width 0)
				(type default)
			)
			(fill no)
			(layer "F.CrtYd")
		)
		(fp_rect
			(start -0.4318 0.9525)
			(end 0.4318 -0.9525)
			(stroke
				(width 0)
				(type default)
			)
			(fill no)
			(layer "F.Fab")
		)
		(pad "1" smd custom
			(at 0 -0.4445)
			(size 0.1524 0.1524)
			(layers "F.Cu" "F.Mask" "F.Paste")
			(net "P3V3_DEV_VFB")
			(options
				(clearance outline)
				(anchor circle)
			)
			(primitives
				(gr_poly
					(pts
						(arc
							(start 0.3048 -0.2032)
							(mid 0.275042 -0.275042)
							(end 0.2032 -0.3048)
						)
						(arc
							(start -0.2032 -0.3048)
							(mid -0.275042 -0.275042)
							(end -0.3048 -0.2032)
						)
						(arc
							(start -0.3048 0.2032)
							(mid -0.275042 0.275042)
							(end -0.2032 0.3048)
						)
						(arc
							(start 0.2032 0.3048)
							(mid 0.275042 0.275042)
							(end 0.3048 0.2032)
						)
					)
					(width 0)
					(fill yes)
				)
			)
		)
		(pad "2" smd custom
			(at 0 0.4445)
			(size 0.1524 0.1524)
			(layers "F.Cu" "F.Mask" "F.Paste")
			(net "P3V3_DEV_VFB_R")
			(options
				(clearance outline)
				(anchor circle)
			)
			(primitives
				(gr_poly
					(pts
						(arc
							(start 0.3048 -0.2032)
							(mid 0.275042 -0.275042)
							(end 0.2032 -0.3048)
						)
						(arc
							(start -0.2032 -0.3048)
							(mid -0.275042 -0.275042)
							(end -0.3048 -0.2032)
						)
						(arc
							(start -0.3048 0.2032)
							(mid -0.275042 0.275042)
							(end -0.2032 0.3048)
						)
						(arc
							(start 0.2032 0.3048)
							(mid 0.275042 0.275042)
							(end 0.3048 0.2032)
						)
					)
					(width 0)
					(fill yes)
				)
			)
		)
	)
)
